# T6G (Grand Teton) — schematic netlist excerpt (pin names and nets, part order shuffled) for the footprints in the layout excerpt that follows; sources: Cadence DE-HDL packaged netlist, KiCad conversion of 04192023_DAF0TMB3IC0_F0TG_MB_C_brd_V02_OCP.brd

PR883  Q_RES  0 5% EMPTY  pkg 0402LF  page 362 : A = TP_P0V9_RETIMER_CPU0_SVID_ALERT_N ; B = GND
C8014  Q_CAP  100NF 50V 10% EMPTY  pkg C0402  page 267 : A = OC_P2V5_COMP ; B = GND

(kicad_pcb
	(version 20260206)
	(generator "pcbnew")
	(generator_version "10.0")
	(general
		(thickness 1.6)
		(legacy_teardrops no)
	)
	(paper "A4")
	(title_block
		(title "04192023_DAF0TMB3IC0_F0TG_MB_C_brd_V02_OCP.brd")
		(comment 1 "Grand Teton / footprints 5204-5205 of 8354")
	)
	(layers
		(0 "F.Cu" signal "TOP")
		(4 "In1.Cu" signal "GND")
		(6 "In2.Cu" signal "IN1")
		(8 "In3.Cu" signal "GND1")
		(10 "In4.Cu" signal "IN2")
		(12 "In5.Cu" signal "GND2")
		(14 "In6.Cu" signal "IN3")
		(16 "In7.Cu" signal "GND3")
		(18 "In8.Cu" signal "VCC")
		(20 "In9.Cu" signal "VCC1")
		(22 "In10.Cu" signal "GND4")
		(24 "In11.Cu" signal "IN4")
		(26 "In12.Cu" signal "GND5")
		(28 "In13.Cu" signal "IN5")
		(30 "In14.Cu" signal "GND6")
		(32 "In15.Cu" signal "IN6")
		(34 "In16.Cu" signal "GND7")
		(2 "B.Cu" signal "BOTTOM")
		(9 "F.Adhes" user "F.Adhesive")
		(11 "B.Adhes" user "B.Adhesive")
		(13 "F.Paste" user "Package Geometry/Pastemask Top")
		(15 "B.Paste" user "Package Geometry/Pastemask Bottom")
		(5 "F.SilkS" user "Ref Des/Silkscreen Top")
		(7 "B.SilkS" user "Ref Des/Silkscreen Bottom")
		(1 "F.Mask" user "Board Geometry/Soldermask Top")
		(3 "B.Mask" user "Board Geometry/Soldermask Bottom")
		(17 "Dwgs.User" user "User.Drawings")
		(19 "Cmts.User" user "User.Comments")
		(21 "Eco1.User" user "User.Eco1")
		(23 "Eco2.User" user "User.Eco2")
		(25 "Edge.Cuts" user "Board Geometry/Outline")
		(27 "Margin" user)
		(31 "F.CrtYd" user "Package Geometry/Place Bound Top")
		(29 "B.CrtYd" user "Package Geometry/Place Bound Bottom")
		(35 "F.Fab" user "Ref Des/Assembly Top")
		(33 "B.Fab" user "Ref Des/Assembly Bottom")
	)
	(footprint ""
		(layer "B.Cu")
		(at 439.029602 -421.37711)
		(property "Reference" "PR883"
			(at 0 0 0)
			(layer "B.SilkS")
			(hide yes)
			(effects
				(font
					(size 1.27 1.27)
				)
				(justify mirror)
			)
		)
		(property "Value" ""
			(at 0 0 0)
			(layer "B.Fab")
			(effects
				(font
					(size 1.27 1.27)
				)
				(justify mirror)
			)
		)
		(duplicate_pad_numbers_are_jumpers no)
		(fp_line
			(start -0.7874 -0.4064)
			(end -0.7874 0.4064)
			(stroke
				(width 0.1524)
				(type default)
			)
			(layer "B.SilkS")
		)
		(fp_line
			(start -0.7874 0.4064)
			(end 0.7874 0.4064)
			(stroke
				(width 0.1524)
				(type default)
			)
			(layer "B.SilkS")
		)
		(fp_line
			(start 0.7874 -0.4064)
			(end -0.7874 -0.4064)
			(stroke
				(width 0.1524)
				(type default)
			)
			(layer "B.SilkS")
		)
		(fp_line
			(start 0.7874 0.4064)
			(end 0.7874 -0.4064)
			(stroke
				(width 0.1524)
				(type default)
			)
			(layer "B.SilkS")
		)
		(fp_line
			(start -0.67945 -0.3048)
			(end -0.67945 0.3048)
			(stroke
				(width 0.1)
				(type default)
			)
			(layer "B.Fab")
		)
		(fp_line
			(start -0.67945 0.3048)
			(end -0.120396 0.3048)
			(stroke
				(width 0.1)
				(type default)
			)
			(layer "B.Fab")
		)
		(fp_line
			(start -0.12065 -0.3048)
			(end -0.67945 -0.3048)
			(stroke
				(width 0.1)
				(type default)
			)
			(layer "B.Fab")
		)
		(fp_line
			(start -0.12065 -0.2794)
			(end -0.12065 -0.3048)
			(stroke
				(width 0.1)
				(type default)
			)
			(layer "B.Fab")
		)
		(fp_line
			(start -0.120396 0.2794)
			(end 0.12065 0.2794)
			(stroke
				(width 0.1)
				(type default)
			)
			(layer "B.Fab")
		)
		(fp_line
			(start -0.120396 0.3048)
			(end -0.120396 0.2794)
			(stroke
				(width 0.1)
				(type default)
			)
			(layer "B.Fab")
		)
		(fp_line
			(start 0.12065 -0.305054)
			(end 0.12065 -0.2794)
			(stroke
				(width 0.1)
				(type default)
			)
			(layer "B.Fab")
		)
		(fp_line
			(start 0.12065 -0.2794)
			(end -0.12065 -0.2794)
			(stroke
				(width 0.1)
				(type default)
			)
			(layer "B.Fab")
		)
		(fp_line
			(start 0.12065 0.2794)
			(end 0.12065 0.3048)
			(stroke
				(width 0.1)
				(type default)
			)
			(layer "B.Fab")
		)
		(fp_line
			(start 0.12065 0.3048)
			(end 0.67945 0.3048)
			(stroke
				(width 0.1)
				(type default)
			)
			(layer "B.Fab")
		)
		(fp_line
			(start 0.67945 -0.305054)
			(end 0.12065 -0.305054)
			(stroke
				(width 0.1)
				(type default)
			)
			(layer "B.Fab")
		)
		(fp_line
			(start 0.67945 0.3048)
			(end 0.67945 -0.305054)
			(stroke
				(width 0.1)
				(type default)
			)
			(layer "B.Fab")
		)
		(pad "1" smd circle
			(at 0.40005 0 180)
			(size 0 0)
			(layers "B.Cu" "B.Mask" "B.Paste")
			(net "TP_P0V9_RETIMER_CPU0_SVID_ALERT_N")
		)
		(pad "2" smd circle
			(at -0.40005 0 180)
			(size 0 0)
			(layers "B.Cu" "B.Mask" "B.Paste")
			(net "GND")
		)
	)
	(footprint ""
		(layer "B.Cu")
		(at 187.071 -422.402)
		(property "Reference" "C8014"
			(at 0 0 0)
			(layer "B.SilkS")
			(hide yes)
			(effects
				(font
					(size 1.27 1.27)
				)
				(justify mirror)
			)
		)
		(property "Value" ""
			(at 0 0 0)
			(layer "B.Fab")
			(effects
				(font
					(size 1.27 1.27)
				)
				(justify mirror)
			)
		)
		(duplicate_pad_numbers_are_jumpers no)
		(fp_line
			(start -0.7874 -0.4064)
			(end -0.7874 0.4064)
			(stroke
				(width 0.1524)
				(type default)
			)
			(layer "B.SilkS")
		)
		(fp_line
			(start -0.7874 0.4064)
			(end 0.7874 0.4064)
			(stroke
				(width 0.1524)
				(type default)
			)
			(layer "B.SilkS")
		)
		(fp_line
			(start 0.7874 -0.4064)
			(end -0.7874 -0.4064)
			(stroke
				(width 0.1524)
				(type default)
			)
			(layer "B.SilkS")
		)
		(fp_line
			(start 0.7874 0.4064)
			(end 0.7874 -0.4064)
			(stroke
				(width 0.1524)
				(type default)
			)
			(layer "B.SilkS")
		)
		(fp_line
			(start -0.67945 -0.3048)
			(end -0.67945 0.3048)
			(stroke
				(width 0.1)
				(type default)
			)
			(layer "B.Fab")
		)
		(fp_line
			(start -0.67945 0.3048)
			(end -0.120396 0.3048)
			(stroke
				(width 0.1)
				(type default)
			)
			(layer "B.Fab")
		)
		(fp_line
			(start -0.12065 -0.3048)
			(end -0.67945 -0.3048)
			(stroke
				(width 0.1)
				(type default)
			)
			(layer "B.Fab")
		)
		(fp_line
			(start -0.12065 -0.2794)
			(end -0.12065 -0.3048)
			(stroke
				(width 0.1)
				(type default)
			)
			(layer "B.Fab")
		)
		(fp_line
			(start -0.120396 0.2794)
			(end 0.12065 0.2794)
			(stroke
				(width 0.1)
				(type default)
			)
			(layer "B.Fab")
		)
		(fp_line
			(start -0.120396 0.3048)
			(end -0.120396 0.2794)
			(stroke
				(width 0.1)
				(type default)
			)
			(layer "B.Fab")
		)
		(fp_line
			(start 0.12065 -0.305054)
			(end 0.12065 -0.2794)
			(stroke
				(width 0.1)
				(type default)
			)
			(layer "B.Fab")
		)
		(fp_line
			(start 0.12065 -0.2794)
			(end -0.12065 -0.2794)
			(stroke
				(width 0.1)
				(type default)
			)
			(layer "B.Fab")
		)
		(fp_line
			(start 0.12065 0.2794)
			(end 0.12065 0.3048)
			(stroke
				(width 0.1)
				(type default)
			)
			(layer "B.Fab")
		)
		(fp_line
			(start 0.12065 0.3048)
			(end 0.67945 0.3048)
			(stroke
				(width 0.1)
				(type default)
			)
			(layer "B.Fab")
		)
		(fp_line
			(start 0.67945 -0.305054)
			(end 0.12065 -0.305054)
			(stroke
				(width 0.1)
				(type default)
			)
			(layer "B.Fab")
		)
		(fp_line
			(start 0.67945 0.3048)
			(end 0.67945 -0.305054)
			(stroke
				(width 0.1)
				(type default)
			)
			(layer "B.Fab")
		)
		(pad "1" smd circle
			(at 0.40005 0 180)
			(size 0 0)
			(layers "B.Cu" "B.Mask" "B.Paste")
			(net "OC_P2V5_COMP")
		)
		(pad "2" smd circle
			(at -0.40005 0 180)
			(size 0 0)
			(layers "B.Cu" "B.Mask" "B.Paste")
			(net "GND")
		)
	)
)
